(kicad_pcb
	(version 20260206)
	(generator "pcbnew")
	(generator_version "10.0")
	(general
		(thickness 1.6)
		(legacy_teardrops no)
	)
	(paper "A4")
	(title_block
		(title "9054_F0T_PDB_BD_GPU_F_V04_1213_1550_OCP.brd")
		(comment 1 "Grand Teton / footprints 144-149 of 608")
	)
	(layers
		(0 "F.Cu" signal "TOP")
		(4 "In1.Cu" signal "GND")
		(6 "In2.Cu" signal "IN1")
		(8 "In3.Cu" signal "GND1")
		(10 "In4.Cu" signal "VCC")
		(12 "In5.Cu" signal "VCC1")
		(14 "In6.Cu" signal "GND2")
		(16 "In7.Cu" signal "IN2")
		(18 "In8.Cu" signal "GND3")
		(2 "B.Cu" signal "BOTTOM")
		(9 "F.Adhes" user "F.Adhesive")
		(11 "B.Adhes" user "B.Adhesive")
		(13 "F.Paste" user "Package Geometry/Pastemask Top")
		(15 "B.Paste" user "Package Geometry/Pastemask Bottom")
		(5 "F.SilkS" user "Ref Des/Silkscreen Top")
		(7 "B.SilkS" user "Ref Des/Silkscreen Bottom")
		(1 "F.Mask" user "Board Geometry/Soldermask Top")
		(3 "B.Mask" user "Board Geometry/Soldermask Bottom")
		(17 "Dwgs.User" user "User.Drawings")
		(19 "Cmts.User" user "User.Comments")
		(21 "Eco1.User" user "User.Eco1")
		(23 "Eco2.User" user "User.Eco2")
		(25 "Edge.Cuts" user "Board Geometry/Outline")
		(27 "Margin" user)
		(31 "F.CrtYd" user "Package Geometry/Place Bound Top")
		(29 "B.CrtYd" user "Package Geometry/Place Bound Bottom")
		(35 "F.Fab" user "Ref Des/Assembly Top")
		(33 "B.Fab" user "Ref Des/Assembly Bottom")
	)
	(footprint ""
		(layer "F.Cu")
		(at 175.26 -45.339 180)
		(property "Reference" "R385"
			(at 0 0 180)
			(layer "F.SilkS")
			(hide yes)
			(effects
				(font
					(size 1.27 1.27)
				)
			)
		)
		(property "Value" ""
			(at 0 0 180)
			(layer "F.Fab")
			(effects
				(font
					(size 1.27 1.27)
				)
			)
		)
		(duplicate_pad_numbers_are_jumpers no)
		(fp_line
			(start 0.7874 0.4064)
			(end -0.7874 0.4064)
			(stroke
				(width 0.1524)
				(type default)
			)
			(layer "F.SilkS")
		)
		(fp_line
			(start 0.7874 -0.4064)
			(end 0.7874 0.4064)
			(stroke
				(width 0.1524)
				(type default)
			)
			(layer "F.SilkS")
		)
		(fp_line
			(start -0.7874 0.4064)
			(end -0.7874 -0.4064)
			(stroke
				(width 0.1524)
				(type default)
			)
			(layer "F.SilkS")
		)
		(fp_line
			(start -0.7874 -0.4064)
			(end 0.7874 -0.4064)
			(stroke
				(width 0.1524)
				(type default)
			)
			(layer "F.SilkS")
		)
		(fp_line
			(start 0.67945 0.3048)
			(end 0.120396 0.3048)
			(stroke
				(width 0.1)
				(type default)
			)
			(layer "F.Fab")
		)
		(fp_line
			(start 0.67945 -0.3048)
			(end 0.67945 0.3048)
			(stroke
				(width 0.1)
				(type default)
			)
			(layer "F.Fab")
		)
		(fp_line
			(start 0.12065 -0.2794)
			(end 0.12065 -0.3048)
			(stroke
				(width 0.1)
				(type default)
			)
			(layer "F.Fab")
		)
		(fp_line
			(start 0.12065 -0.3048)
			(end 0.67945 -0.3048)
			(stroke
				(width 0.1)
				(type default)
			)
			(layer "F.Fab")
		)
		(fp_line
			(start 0.120396 0.3048)
			(end 0.120396 0.2794)
			(stroke
				(width 0.1)
				(type default)
			)
			(layer "F.Fab")
		)
		(fp_line
			(start 0.120396 0.2794)
			(end -0.12065 0.2794)
			(stroke
				(width 0.1)
				(type default)
			)
			(layer "F.Fab")
		)
		(fp_line
			(start -0.12065 0.3048)
			(end -0.67945 0.3048)
			(stroke
				(width 0.1)
				(type default)
			)
			(layer "F.Fab")
		)
		(fp_line
			(start -0.12065 0.2794)
			(end -0.12065 0.3048)
			(stroke
				(width 0.1)
				(type default)
			)
			(layer "F.Fab")
		)
		(fp_line
			(start -0.12065 -0.2794)
			(end 0.12065 -0.2794)
			(stroke
				(width 0.1)
				(type default)
			)
			(layer "F.Fab")
		)
		(fp_line
			(start -0.12065 -0.305054)
			(end -0.12065 -0.2794)
			(stroke
				(width 0.1)
				(type default)
			)
			(layer "F.Fab")
		)
		(fp_line
			(start -0.67945 0.3048)
			(end -0.67945 -0.305054)
			(stroke
				(width 0.1)
				(type default)
			)
			(layer "F.Fab")
		)
		(fp_line
			(start -0.67945 -0.305054)
			(end -0.12065 -0.305054)
			(stroke
				(width 0.1)
				(type default)
			)
			(layer "F.Fab")
		)
		(pad "1" smd circle
			(at -0.40005 0 180)
			(size 0 0)
			(layers "F.Cu" "F.Mask" "F.Paste")
			(net "GPU_HSC2_BUF_EN_N")
		)
		(pad "2" smd circle
			(at 0.40005 0 180)
			(size 0 0)
			(layers "F.Cu" "F.Mask" "F.Paste")
			(net "GND")
		)
	)
	(footprint ""
		(layer "F.Cu")
		(at 435.5338 -23.749 180)
		(property "Reference" "R60"
			(at 0 0 180)
			(layer "F.SilkS")
			(hide yes)
			(effects
				(font
					(size 1.27 1.27)
				)
			)
		)
		(property "Value" ""
			(at 0 0 180)
			(layer "F.Fab")
			(effects
				(font
					(size 1.27 1.27)
				)
			)
		)
		(duplicate_pad_numbers_are_jumpers no)
		(fp_line
			(start 0.7874 0.4064)
			(end -0.7874 0.4064)
			(stroke
				(width 0.1524)
				(type default)
			)
			(layer "F.SilkS")
		)
		(fp_line
			(start 0.7874 -0.4064)
			(end 0.7874 0.4064)
			(stroke
				(width 0.1524)
				(type default)
			)
			(layer "F.SilkS")
		)
		(fp_line
			(start -0.7874 0.4064)
			(end -0.7874 -0.4064)
			(stroke
				(width 0.1524)
				(type default)
			)
			(layer "F.SilkS")
		)
		(fp_line
			(start -0.7874 -0.4064)
			(end 0.7874 -0.4064)
			(stroke
				(width 0.1524)
				(type default)
			)
			(layer "F.SilkS")
		)
		(fp_line
			(start 0.67945 0.3048)
			(end 0.120396 0.3048)
			(stroke
				(width 0.1)
				(type default)
			)
			(layer "F.Fab")
		)
		(fp_line
			(start 0.67945 -0.3048)
			(end 0.67945 0.3048)
			(stroke
				(width 0.1)
				(type default)
			)
			(layer "F.Fab")
		)
		(fp_line
			(start 0.12065 -0.2794)
			(end 0.12065 -0.3048)
			(stroke
				(width 0.1)
				(type default)
			)
			(layer "F.Fab")
		)
		(fp_line
			(start 0.12065 -0.3048)
			(end 0.67945 -0.3048)
			(stroke
				(width 0.1)
				(type default)
			)
			(layer "F.Fab")
		)
		(fp_line
			(start 0.120396 0.3048)
			(end 0.120396 0.2794)
			(stroke
				(width 0.1)
				(type default)
			)
			(layer "F.Fab")
		)
		(fp_line
			(start 0.120396 0.2794)
			(end -0.12065 0.2794)
			(stroke
				(width 0.1)
				(type default)
			)
			(layer "F.Fab")
		)
		(fp_line
			(start -0.12065 0.3048)
			(end -0.67945 0.3048)
			(stroke
				(width 0.1)
				(type default)
			)
			(layer "F.Fab")
		)
		(fp_line
			(start -0.12065 0.2794)
			(end -0.12065 0.3048)
			(stroke
				(width 0.1)
				(type default)
			)
			(layer "F.Fab")
		)
		(fp_line
			(start -0.12065 -0.2794)
			(end 0.12065 -0.2794)
			(stroke
				(width 0.1)
				(type default)
			)
			(layer "F.Fab")
		)
		(fp_line
			(start -0.12065 -0.305054)
			(end -0.12065 -0.2794)
			(stroke
				(width 0.1)
				(type default)
			)
			(layer "F.Fab")
		)
		(fp_line
			(start -0.67945 0.3048)
			(end -0.67945 -0.305054)
			(stroke
				(width 0.1)
				(type default)
			)
			(layer "F.Fab")
		)
		(fp_line
			(start -0.67945 -0.305054)
			(end -0.12065 -0.305054)
			(stroke
				(width 0.1)
				(type default)
			)
			(layer "F.Fab")
		)
		(pad "1" smd circle
			(at -0.40005 0 180)
			(size 0 0)
			(layers "F.Cu" "F.Mask" "F.Paste")
			(net "P3V3_AUX")
		)
		(pad "2" smd circle
			(at 0.40005 0 180)
			(size 0 0)
			(layers "F.Cu" "F.Mask" "F.Paste")
			(net "FRU_ADDR1")
		)
	)
	(footprint ""
		(layer "F.Cu")
		(at 414.4264 -38.862 90)
		(property "Reference" "U30"
			(at -1.30937 1.6891 0)
			(unlocked yes)
			(layer "F.SilkS")
			(effects
				(font
					(size 0.7874 0.5842)
					(thickness 0.1524)
				)
				(justify left)
			)
		)
		(property "Value" ""
			(at 0 0 90)
			(layer "F.Fab")
			(effects
				(font
					(size 1.27 1.27)
				)
			)
		)
		(duplicate_pad_numbers_are_jumpers no)
		(fp_line
			(start 1.603248 -1.500124)
			(end 1.603248 1.500124)
			(stroke
				(width 0.1524)
				(type default)
			)
			(layer "F.SilkS")
		)
		(fp_line
			(start -1.603248 -1.500124)
			(end 1.603248 -1.500124)
			(stroke
				(width 0.1524)
				(type default)
			)
			(layer "F.SilkS")
		)
		(fp_line
			(start 1.603248 1.500124)
			(end -1.603248 1.500124)
			(stroke
				(width 0.1524)
				(type default)
			)
			(layer "F.SilkS")
		)
		(fp_line
			(start -1.603248 1.500124)
			(end -1.603248 -1.500124)
			(stroke
				(width 0.1524)
				(type default)
			)
			(layer "F.SilkS")
		)
		(fp_line
			(start 0.700024 -1.500124)
			(end -0.700024 -1.500124)
			(stroke
				(width 0.1)
				(type default)
			)
			(layer "F.Fab")
		)
		(fp_line
			(start -0.700024 -1.500124)
			(end -0.700024 -1.169924)
			(stroke
				(width 0.1)
				(type default)
			)
			(layer "F.Fab")
		)
		(fp_line
			(start -0.700024 -1.169924)
			(end -1.249934 -1.169924)
			(stroke
				(width 0.1)
				(type default)
			)
			(layer "F.Fab")
		)
		(fp_line
			(start -1.249934 -1.169924)
			(end -1.249934 -0.729996)
			(stroke
				(width 0.1)
				(type default)
			)
			(layer "F.Fab")
		)
		(fp_line
			(start -0.6985 -0.729996)
			(end -0.6985 0.729996)
			(stroke
				(width 0.1)
				(type default)
			)
			(layer "F.Fab")
		)
		(fp_line
			(start -1.249934 -0.729996)
			(end -0.6985 -0.729996)
			(stroke
				(width 0.1)
				(type default)
			)
			(layer "F.Fab")
		)
		(fp_line
			(start 1.249934 -0.219964)
			(end 0.700024 -0.219964)
			(stroke
				(width 0.1)
				(type default)
			)
			(layer "F.Fab")
		)
		(fp_line
			(start 0.700024 -0.219964)
			(end 0.700024 -1.500124)
			(stroke
				(width 0.1)
				(type default)
			)
			(layer "F.Fab")
		)
		(fp_line
			(start 1.249934 0.219964)
			(end 1.249934 -0.219964)
			(stroke
				(width 0.1)
				(type default)
			)
			(layer "F.Fab")
		)
		(fp_line
			(start 0.700024 0.219964)
			(end 1.249934 0.219964)
			(stroke
				(width 0.1)
				(type default)
			)
			(layer "F.Fab")
		)
		(fp_line
			(start -0.6985 0.729996)
			(end -1.249934 0.729996)
			(stroke
				(width 0.1)
				(type default)
			)
			(layer "F.Fab")
		)
		(fp_line
			(start -1.249934 0.729996)
			(end -1.249934 1.169924)
			(stroke
				(width 0.1)
				(type default)
			)
			(layer "F.Fab")
		)
		(fp_line
			(start -0.700024 1.169924)
			(end -0.700024 1.500124)
			(stroke
				(width 0.1)
				(type default)
			)
			(layer "F.Fab")
		)
		(fp_line
			(start -1.249934 1.169924)
			(end -0.700024 1.169924)
			(stroke
				(width 0.1)
				(type default)
			)
			(layer "F.Fab")
		)
		(fp_line
			(start 0.700024 1.500124)
			(end 0.700024 0.219964)
			(stroke
				(width 0.1)
				(type default)
			)
			(layer "F.Fab")
		)
		(fp_line
			(start -0.700024 1.500124)
			(end 0.700024 1.500124)
			(stroke
				(width 0.1)
				(type default)
			)
			(layer "F.Fab")
		)
		(fp_rect
			(start -0.700024 1.500124)
			(end 0.700024 -1.500124)
			(stroke
				(width 0)
				(type default)
			)
			(fill no)
			(layer "F.Fab")
		)
		(pad "D" smd rect
			(at 0.999998 0)
			(size 0.8128 0.9144)
			(layers "F.Cu" "F.Mask" "F.Paste")
			(net "PWRGD_P52V_HS2_4287_PG")
		)
		(pad "G" smd rect
			(at -0.999998 -0.94996)
			(size 0.8128 0.9144)
			(layers "F.Cu" "F.Mask" "F.Paste")
			(net "PWRGD_P52V_HS2_4287_PG_R_N")
		)
		(pad "S" smd rect
			(at -0.999998 0.94996)
			(size 0.8128 0.9144)
			(layers "F.Cu" "F.Mask" "F.Paste")
			(net "GND")
		)
	)
	(footprint ""
		(layer "F.Cu")
		(at 449.199 -44.196 180)
		(property "Reference" "R186"
			(at 0 0 180)
			(layer "F.SilkS")
			(hide yes)
			(effects
				(font
					(size 1.27 1.27)
				)
			)
		)
		(property "Value" ""
			(at 0 0 180)
			(layer "F.Fab")
			(effects
				(font
					(size 1.27 1.27)
				)
			)
		)
		(duplicate_pad_numbers_are_jumpers no)
		(fp_line
			(start 0.7874 0.4064)
			(end -0.7874 0.4064)
			(stroke
				(width 0.1524)
				(type default)
			)
			(layer "F.SilkS")
		)
		(fp_line
			(start 0.7874 -0.4064)
			(end 0.7874 0.4064)
			(stroke
				(width 0.1524)
				(type default)
			)
			(layer "F.SilkS")
		)
		(fp_line
			(start -0.7874 0.4064)
			(end -0.7874 -0.4064)
			(stroke
				(width 0.1524)
				(type default)
			)
			(layer "F.SilkS")
		)
		(fp_line
			(start -0.7874 -0.4064)
			(end 0.7874 -0.4064)
			(stroke
				(width 0.1524)
				(type default)
			)
			(layer "F.SilkS")
		)
		(fp_line
			(start 0.67945 0.3048)
			(end 0.120396 0.3048)
			(stroke
				(width 0.1)
				(type default)
			)
			(layer "F.Fab")
		)
		(fp_line
			(start 0.67945 -0.3048)
			(end 0.67945 0.3048)
			(stroke
				(width 0.1)
				(type default)
			)
			(layer "F.Fab")
		)
		(fp_line
			(start 0.12065 -0.2794)
			(end 0.12065 -0.3048)
			(stroke
				(width 0.1)
				(type default)
			)
			(layer "F.Fab")
		)
		(fp_line
			(start 0.12065 -0.3048)
			(end 0.67945 -0.3048)
			(stroke
				(width 0.1)
				(type default)
			)
			(layer "F.Fab")
		)
		(fp_line
			(start 0.120396 0.3048)
			(end 0.120396 0.2794)
			(stroke
				(width 0.1)
				(type default)
			)
			(layer "F.Fab")
		)
		(fp_line
			(start 0.120396 0.2794)
			(end -0.12065 0.2794)
			(stroke
				(width 0.1)
				(type default)
			)
			(layer "F.Fab")
		)
		(fp_line
			(start -0.12065 0.3048)
			(end -0.67945 0.3048)
			(stroke
				(width 0.1)
				(type default)
			)
			(layer "F.Fab")
		)
		(fp_line
			(start -0.12065 0.2794)
			(end -0.12065 0.3048)
			(stroke
				(width 0.1)
				(type default)
			)
			(layer "F.Fab")
		)
		(fp_line
			(start -0.12065 -0.2794)
			(end 0.12065 -0.2794)
			(stroke
				(width 0.1)
				(type default)
			)
			(layer "F.Fab")
		)
		(fp_line
			(start -0.12065 -0.305054)
			(end -0.12065 -0.2794)
			(stroke
				(width 0.1)
				(type default)
			)
			(layer "F.Fab")
		)
		(fp_line
			(start -0.67945 0.3048)
			(end -0.67945 -0.305054)
			(stroke
				(width 0.1)
				(type default)
			)
			(layer "F.Fab")
		)
		(fp_line
			(start -0.67945 -0.305054)
			(end -0.12065 -0.305054)
			(stroke
				(width 0.1)
				(type default)
			)
			(layer "F.Fab")
		)
		(pad "1" smd circle
			(at -0.40005 0 180)
			(size 0 0)
			(layers "F.Cu" "F.Mask" "F.Paste")
			(net "GND")
		)
		(pad "2" smd circle
			(at 0.40005 0 180)
			(size 0 0)
			(layers "F.Cu" "F.Mask" "F.Paste")
			(net "GPU_HSC_BUF_EN")
		)
	)
	(footprint ""
		(layer "F.Cu")
		(at 263.5504 -48.387 90)
		(property "Reference" "R155"
			(at 0 0 90)
			(layer "F.SilkS")
			(hide yes)
			(effects
				(font
					(size 1.27 1.27)
				)
			)
		)
		(property "Value" ""
			(at 0 0 90)
			(layer "F.Fab")
			(effects
				(font
					(size 1.27 1.27)
				)
			)
		)
		(duplicate_pad_numbers_are_jumpers no)
		(fp_line
			(start 0.7874 -0.4064)
			(end 0.7874 0.4064)
			(stroke
				(width 0.1524)
				(type default)
			)
			(layer "F.SilkS")
		)
		(fp_line
			(start -0.7874 -0.4064)
			(end 0.7874 -0.4064)
			(stroke
				(width 0.1524)
				(type default)
			)
			(layer "F.SilkS")
		)
		(fp_line
			(start 0.7874 0.4064)
			(end -0.7874 0.4064)
			(stroke
				(width 0.1524)
				(type default)
			)
			(layer "F.SilkS")
		)
		(fp_line
			(start -0.7874 0.4064)
			(end -0.7874 -0.4064)
			(stroke
				(width 0.1524)
				(type default)
			)
			(layer "F.SilkS")
		)
		(fp_line
			(start -0.12065 -0.305054)
			(end -0.12065 -0.2794)
			(stroke
				(width 0.1)
				(type default)
			)
			(layer "F.Fab")
		)
		(fp_line
			(start -0.67945 -0.305054)
			(end -0.12065 -0.305054)
			(stroke
				(width 0.1)
				(type default)
			)
			(layer "F.Fab")
		)
		(fp_line
			(start 0.67945 -0.3048)
			(end 0.67945 0.3048)
			(stroke
				(width 0.1)
				(type default)
			)
			(layer "F.Fab")
		)
		(fp_line
			(start 0.12065 -0.3048)
			(end 0.67945 -0.3048)
			(stroke
				(width 0.1)
				(type default)
			)
			(layer "F.Fab")
		)
		(fp_line
			(start 0.12065 -0.2794)
			(end 0.12065 -0.3048)
			(stroke
				(width 0.1)
				(type default)
			)
			(layer "F.Fab")
		)
		(fp_line
			(start -0.12065 -0.2794)
			(end 0.12065 -0.2794)
			(stroke
				(width 0.1)
				(type default)
			)
			(layer "F.Fab")
		)
		(fp_line
			(start 0.120396 0.2794)
			(end -0.12065 0.2794)
			(stroke
				(width 0.1)
				(type default)
			)
			(layer "F.Fab")
		)
		(fp_line
			(start -0.12065 0.2794)
			(end -0.12065 0.3048)
			(stroke
				(width 0.1)
				(type default)
			)
			(layer "F.Fab")
		)
		(fp_line
			(start 0.67945 0.3048)
			(end 0.120396 0.3048)
			(stroke
				(width 0.1)
				(type default)
			)
			(layer "F.Fab")
		)
		(fp_line
			(start 0.120396 0.3048)
			(end 0.120396 0.2794)
			(stroke
				(width 0.1)
				(type default)
			)
			(layer "F.Fab")
		)
		(fp_line
			(start -0.12065 0.3048)
			(end -0.67945 0.3048)
			(stroke
				(width 0.1)
				(type default)
			)
			(layer "F.Fab")
		)
		(fp_line
			(start -0.67945 0.3048)
			(end -0.67945 -0.305054)
			(stroke
				(width 0.1)
				(type default)
			)
			(layer "F.Fab")
		)
		(pad "1" smd circle
			(at -0.40005 0 90)
			(size 0 0)
			(layers "F.Cu" "F.Mask" "F.Paste")
			(net "GPU_HSC1_BUF_EN_N")
		)
		(pad "2" smd circle
			(at 0.40005 0 90)
			(size 0 0)
			(layers "F.Cu" "F.Mask" "F.Paste")
			(net "GND")
		)
	)
	(footprint ""
		(layer "F.Cu")
		(at 436.753 -42.799)
		(property "Reference" "R3"
			(at 0 0 0)
			(layer "F.SilkS")
			(hide yes)
			(effects
				(font
					(size 1.27 1.27)
				)
			)
		)
		(property "Value" ""
			(at 0 0 0)
			(layer "F.Fab")
			(effects
				(font
					(size 1.27 1.27)
				)
			)
		)
		(duplicate_pad_numbers_are_jumpers no)
		(fp_line
			(start -0.7874 -0.4064)
			(end 0.7874 -0.4064)
			(stroke
				(width 0.1524)
				(type default)
			)
			(layer "F.SilkS")
		)
		(fp_line
			(start -0.7874 0.4064)
			(end -0.7874 -0.4064)
			(stroke
				(width 0.1524)
				(type default)
			)
			(layer "F.SilkS")
		)
		(fp_line
			(start 0.7874 -0.4064)
			(end 0.7874 0.4064)
			(stroke
				(width 0.1524)
				(type default)
			)
			(layer "F.SilkS")
		)
		(fp_line
			(start 0.7874 0.4064)
			(end -0.7874 0.4064)
			(stroke
				(width 0.1524)
				(type default)
			)
			(layer "F.SilkS")
		)
		(fp_line
			(start -0.67945 -0.305054)
			(end -0.12065 -0.305054)
			(stroke
				(width 0.1)
				(type default)
			)
			(layer "F.Fab")
		)
		(fp_line
			(start -0.67945 0.3048)
			(end -0.67945 -0.305054)
			(stroke
				(width 0.1)
				(type default)
			)
			(layer "F.Fab")
		)
		(fp_line
			(start -0.12065 -0.305054)
			(end -0.12065 -0.2794)
			(stroke
				(width 0.1)
				(type default)
			)
			(layer "F.Fab")
		)
		(fp_line
			(start -0.12065 -0.2794)
			(end 0.12065 -0.2794)
			(stroke
				(width 0.1)
				(type default)
			)
			(layer "F.Fab")
		)
		(fp_line
			(start -0.12065 0.2794)
			(end -0.12065 0.3048)
			(stroke
				(width 0.1)
				(type default)
			)
			(layer "F.Fab")
		)
		(fp_line
			(start -0.12065 0.3048)
			(end -0.67945 0.3048)
			(stroke
				(width 0.1)
				(type default)
			)
			(layer "F.Fab")
		)
		(fp_line
			(start 0.120396 0.2794)
			(end -0.12065 0.2794)
			(stroke
				(width 0.1)
				(type default)
			)
			(layer "F.Fab")
		)
		(fp_line
			(start 0.120396 0.3048)
			(end 0.120396 0.2794)
			(stroke
				(width 0.1)
				(type default)
			)
			(layer "F.Fab")
		)
		(fp_line
			(start 0.12065 -0.3048)
			(end 0.67945 -0.3048)
			(stroke
				(width 0.1)
				(type default)
			)
			(layer "F.Fab")
		)
		(fp_line
			(start 0.12065 -0.2794)
			(end 0.12065 -0.3048)
			(stroke
				(width 0.1)
				(type default)
			)
			(layer "F.Fab")
		)
		(fp_line
			(start 0.67945 -0.3048)
			(end 0.67945 0.3048)
			(stroke
				(width 0.1)
				(type default)
			)
			(layer "F.Fab")
		)
		(fp_line
			(start 0.67945 0.3048)
			(end 0.120396 0.3048)
			(stroke
				(width 0.1)
				(type default)
			)
			(layer "F.Fab")
		)
		(pad "1" smd circle
			(at -0.40005 0)
			(size 0 0)
			(layers "F.Cu" "F.Mask" "F.Paste")
			(net "PWRGD_P3V3_AUX_MB_BUF")
		)
		(pad "2" smd circle
			(at 0.40005 0)
			(size 0 0)
			(layers "F.Cu" "F.Mask" "F.Paste")
			(net "MB_MISC_I2C_EN")
		)
	)
)
